(kicad_pcb
	(version 20260206)
	(generator "pcbnew")
	(generator_version "10.0")
	(general
		(thickness 1.6)
		(legacy_teardrops no)
	)
	(paper "A4")
	(title_block
		(title "baseboard — 13948-1b.1110WZS1818.brd")
		(comment 1 "Honey Badger (Wiwynn) / footprints 140-147 of 2523")
	)
	(layers
		(0 "F.Cu" signal "TOP")
		(4 "In1.Cu" signal "L2GND")
		(6 "In2.Cu" signal "L3")
		(8 "In3.Cu" signal "L4VCC")
		(10 "In4.Cu" signal "L5VCC")
		(12 "In5.Cu" signal "L6")
		(14 "In6.Cu" signal "L7GND")
		(2 "B.Cu" signal "BOTTOM")
		(9 "F.Adhes" user "F.Adhesive")
		(11 "B.Adhes" user "B.Adhesive")
		(13 "F.Paste" user "Package Geometry/Pastemask Top")
		(15 "B.Paste" user "Package Geometry/Pastemask Bottom")
		(5 "F.SilkS" user "Ref Des/Silkscreen Top")
		(7 "B.SilkS" user "Ref Des/Silkscreen Bottom")
		(1 "F.Mask" user "Board Geometry/Soldermask Top")
		(3 "B.Mask" user "Board Geometry/Soldermask Bottom")
		(17 "Dwgs.User" user "User.Drawings")
		(19 "Cmts.User" user "User.Comments")
		(21 "Eco1.User" user "User.Eco1")
		(23 "Eco2.User" user "User.Eco2")
		(25 "Edge.Cuts" user "Board Geometry/Outline")
		(27 "Margin" user)
		(31 "F.CrtYd" user "Package Geometry/Place Bound Top")
		(29 "B.CrtYd" user "Package Geometry/Place Bound Bottom")
		(35 "F.Fab" user "Ref Des/Assembly Top")
		(33 "B.Fab" user "Ref Des/Assembly Bottom")
	)
	(footprint ""
		(layer "F.Cu")
		(at 94.215966 -63.119)
		(property "Reference" "SR677"
			(at 0 0 0)
			(layer "F.SilkS")
			(hide yes)
			(effects
				(font
					(size 1.27 1.27)
				)
			)
		)
		(property "Value" "4K7R2F-GP"
			(at 0.064008 -3.993896 0)
			(unlocked yes)
			(layer "F.Fab")
			(hide yes)
			(effects
				(font
					(size 1.016 1.016)
					(thickness 0.1524)
				)
			)
		)
		(property "Device Type" "R402H16"
			(at 0.064008 -5.517896 0)
			(unlocked yes)
			(layer "F.Fab")
			(hide yes)
			(effects
				(font
					(size 1.016 1.016)
					(thickness 0.1524)
				)
			)
		)
		(duplicate_pad_numbers_are_jumpers no)
		(fp_line
			(start -0.508 -0.9398)
			(end -0.508 0.9398)
			(stroke
				(width 0.1524)
				(type default)
			)
			(layer "F.SilkS")
		)
		(fp_line
			(start 0.508 -0.9398)
			(end -0.508 -0.9398)
			(stroke
				(width 0.1524)
				(type default)
			)
			(layer "F.SilkS")
		)
		(fp_rect
			(start -0.508 0.9398)
			(end 0.508 -0.9398)
			(stroke
				(width 0)
				(type default)
			)
			(fill no)
			(layer "F.CrtYd")
		)
		(fp_rect
			(start -0.508 0.9398)
			(end 0.508 -0.9398)
			(stroke
				(width 0)
				(type default)
			)
			(fill no)
			(layer "F.Fab")
		)
		(pad "1" smd custom
			(at 0 -0.4445)
			(size 0.1397 0.1397)
			(layers "F.Cu" "F.Mask" "F.Paste")
			(net "P1V8_C")
			(options
				(clearance outline)
				(anchor circle)
			)
			(primitives
				(gr_poly
					(pts
						(arc
							(start -0.1778 -0.2794)
							(mid -0.249642 -0.249642)
							(end -0.2794 -0.1778)
						)
						(arc
							(start -0.2794 0.1778)
							(mid -0.249642 0.249642)
							(end -0.1778 0.2794)
						)
						(arc
							(start 0.1778 0.2794)
							(mid 0.249642 0.249642)
							(end 0.2794 0.1778)
						)
						(arc
							(start 0.2794 -0.1778)
							(mid 0.249642 -0.249642)
							(end 0.1778 -0.2794)
						)
					)
					(width 0)
					(fill yes)
				)
			)
		)
		(pad "2" smd custom
			(at 0 0.4445)
			(size 0.1397 0.1397)
			(layers "F.Cu" "F.Mask" "F.Paste")
			(net "ICE0_TDI")
			(options
				(clearance outline)
				(anchor circle)
			)
			(primitives
				(gr_poly
					(pts
						(arc
							(start -0.1778 -0.2794)
							(mid -0.249642 -0.249642)
							(end -0.2794 -0.1778)
						)
						(arc
							(start -0.2794 0.1778)
							(mid -0.249642 0.249642)
							(end -0.1778 0.2794)
						)
						(arc
							(start 0.1778 0.2794)
							(mid 0.249642 0.249642)
							(end 0.2794 0.1778)
						)
						(arc
							(start 0.2794 -0.1778)
							(mid 0.249642 -0.249642)
							(end 0.1778 -0.2794)
						)
					)
					(width 0)
					(fill yes)
				)
			)
		)
	)
	(footprint ""
		(layer "F.Cu")
		(at 141.49197 -83.566 180)
		(property "Reference" "R611"
			(at 0 0 180)
			(layer "F.SilkS")
			(hide yes)
			(effects
				(font
					(size 1.27 1.27)
				)
			)
		)
		(property "Value" "4K7R2F-GP"
			(at 0.064008 -3.993896 180)
			(unlocked yes)
			(layer "F.Fab")
			(hide yes)
			(effects
				(font
					(size 1.016 1.016)
					(thickness 0.1524)
				)
			)
		)
		(property "Device Type" "R402H16"
			(at 0.064008 -5.517896 180)
			(unlocked yes)
			(layer "F.Fab")
			(hide yes)
			(effects
				(font
					(size 1.016 1.016)
					(thickness 0.1524)
				)
			)
		)
		(duplicate_pad_numbers_are_jumpers no)
		(fp_line
			(start 0.508 -0.9398)
			(end -0.508 -0.9398)
			(stroke
				(width 0.1524)
				(type default)
			)
			(layer "F.SilkS")
		)
		(fp_line
			(start -0.508 -0.9398)
			(end -0.508 0.9398)
			(stroke
				(width 0.1524)
				(type default)
			)
			(layer "F.SilkS")
		)
		(fp_rect
			(start -0.508 0.9398)
			(end 0.508 -0.9398)
			(stroke
				(width 0)
				(type default)
			)
			(fill no)
			(layer "F.CrtYd")
		)
		(fp_rect
			(start -0.508 0.9398)
			(end 0.508 -0.9398)
			(stroke
				(width 0)
				(type default)
			)
			(fill no)
			(layer "F.Fab")
		)
		(pad "1" smd custom
			(at 0 -0.4445 180)
			(size 0.1397 0.1397)
			(layers "F.Cu" "F.Mask" "F.Paste")
			(net "P3V3_STBY")
			(options
				(clearance outline)
				(anchor circle)
			)
			(primitives
				(gr_poly
					(pts
						(arc
							(start -0.1778 -0.2794)
							(mid -0.249642 -0.249642)
							(end -0.2794 -0.1778)
						)
						(arc
							(start -0.2794 0.1778)
							(mid -0.249642 0.249642)
							(end -0.1778 0.2794)
						)
						(arc
							(start 0.1778 0.2794)
							(mid 0.249642 0.249642)
							(end 0.2794 0.1778)
						)
						(arc
							(start 0.2794 -0.1778)
							(mid 0.249642 -0.249642)
							(end 0.1778 -0.2794)
						)
					)
					(width 0)
					(fill yes)
				)
			)
		)
		(pad "2" smd custom
			(at 0 0.4445 180)
			(size 0.1397 0.1397)
			(layers "F.Cu" "F.Mask" "F.Paste")
			(net "TEMP_3_A0")
			(options
				(clearance outline)
				(anchor circle)
			)
			(primitives
				(gr_poly
					(pts
						(arc
							(start -0.1778 -0.2794)
							(mid -0.249642 -0.249642)
							(end -0.2794 -0.1778)
						)
						(arc
							(start -0.2794 0.1778)
							(mid -0.249642 0.249642)
							(end -0.1778 0.2794)
						)
						(arc
							(start 0.1778 0.2794)
							(mid 0.249642 0.249642)
							(end 0.2794 0.1778)
						)
						(arc
							(start 0.2794 -0.1778)
							(mid 0.249642 -0.249642)
							(end 0.1778 -0.2794)
						)
					)
					(width 0)
					(fill yes)
				)
			)
		)
	)
	(footprint ""
		(layer "F.Cu")
		(at 77.8256 -18.3896 180)
		(property "Reference" "PC207"
			(at 0 0 180)
			(layer "F.SilkS")
			(hide yes)
			(effects
				(font
					(size 1.27 1.27)
				)
			)
		)
		(property "Value" "SC1U25V3KX-GP"
			(at 0 -2.8194 180)
			(unlocked yes)
			(layer "F.Fab")
			(hide yes)
			(effects
				(font
					(size 1.016 1.016)
					(thickness 0.1524)
				)
			)
		)
		(property "Device Type" "C603H36"
			(at 0 -4.3434 180)
			(unlocked yes)
			(layer "F.Fab")
			(hide yes)
			(effects
				(font
					(size 1.016 1.016)
					(thickness 0.1524)
				)
			)
		)
		(duplicate_pad_numbers_are_jumpers no)
		(fp_line
			(start 0.508 0)
			(end -0.508 0)
			(stroke
				(width 0.2032)
				(type default)
			)
			(layer "F.SilkS")
		)
		(fp_rect
			(start -0.5842 1.3335)
			(end 0.5842 -1.3335)
			(stroke
				(width 0)
				(type default)
			)
			(fill no)
			(layer "F.CrtYd")
		)
		(fp_rect
			(start -0.5842 1.3335)
			(end 0.5842 -1.3335)
			(stroke
				(width 0)
				(type default)
			)
			(fill no)
			(layer "F.Fab")
		)
		(pad "1" smd custom
			(at 0 -0.762 180)
			(size 0.2159 0.2159)
			(layers "F.Cu" "F.Mask" "F.Paste")
			(net "VT235_VDDH")
			(options
				(clearance outline)
				(anchor circle)
			)
			(primitives
				(gr_poly
					(pts
						(arc
							(start -0.3302 -0.4318)
							(mid -0.402042 -0.402042)
							(end -0.4318 -0.3302)
						)
						(arc
							(start -0.4318 0.3302)
							(mid -0.402042 0.402042)
							(end -0.3302 0.4318)
						)
						(arc
							(start 0.3302 0.4318)
							(mid 0.402042 0.402042)
							(end 0.4318 0.3302)
						)
						(arc
							(start 0.4318 -0.3302)
							(mid 0.402042 -0.402042)
							(end 0.3302 -0.4318)
						)
					)
					(width 0)
					(fill yes)
				)
			)
		)
		(pad "2" smd custom
			(at 0 0.762 180)
			(size 0.2159 0.2159)
			(layers "F.Cu" "F.Mask" "F.Paste")
			(net "GND")
			(options
				(clearance outline)
				(anchor circle)
			)
			(primitives
				(gr_poly
					(pts
						(arc
							(start -0.3302 -0.4318)
							(mid -0.402042 -0.402042)
							(end -0.4318 -0.3302)
						)
						(arc
							(start -0.4318 0.3302)
							(mid -0.402042 0.402042)
							(end -0.3302 0.4318)
						)
						(arc
							(start 0.3302 0.4318)
							(mid 0.402042 0.402042)
							(end 0.4318 0.3302)
						)
						(arc
							(start 0.4318 -0.3302)
							(mid 0.402042 -0.402042)
							(end 0.3302 -0.4318)
						)
					)
					(width 0)
					(fill yes)
				)
			)
		)
	)
	(footprint ""
		(layer "F.Cu")
		(at 152.247092 -109.503464 -90)
		(property "Reference" "SR833"
			(at 0 0 270)
			(layer "F.SilkS")
			(hide yes)
			(effects
				(font
					(size 1.27 1.27)
				)
			)
		)
		(property "Value" "D51R3F-2-GP"
			(at -0.0254 -2.5146 270)
			(unlocked yes)
			(layer "F.Fab")
			(hide yes)
			(effects
				(font
					(size 1.016 1.016)
					(thickness 0.1524)
				)
			)
		)
		(property "Device Type" "R603H22"
			(at -0.0254 -4.0386 270)
			(unlocked yes)
			(layer "F.Fab")
			(hide yes)
			(effects
				(font
					(size 1.016 1.016)
					(thickness 0.1524)
				)
			)
		)
		(duplicate_pad_numbers_are_jumpers no)
		(fp_line
			(start -0.4826 0)
			(end -0.2032 0)
			(stroke
				(width 0.2032)
				(type default)
			)
			(layer "F.SilkS")
		)
		(fp_line
			(start 0.2032 0)
			(end 0.4826 0)
			(stroke
				(width 0.2032)
				(type default)
			)
			(layer "F.SilkS")
		)
		(fp_rect
			(start -0.5842 1.3335)
			(end 0.5842 -1.3335)
			(stroke
				(width 0)
				(type default)
			)
			(fill no)
			(layer "F.CrtYd")
		)
		(fp_rect
			(start -0.5842 1.3335)
			(end 0.5842 -1.3335)
			(stroke
				(width 0)
				(type default)
			)
			(fill no)
			(layer "F.Fab")
		)
		(pad "1" smd custom
			(at 0 -0.762 270)
			(size 0.2159 0.2159)
			(layers "F.Cu" "F.Mask" "F.Paste")
			(net "P0V9_E")
			(options
				(clearance outline)
				(anchor circle)
			)
			(primitives
				(gr_poly
					(pts
						(arc
							(start -0.3302 -0.4318)
							(mid -0.402042 -0.402042)
							(end -0.4318 -0.3302)
						)
						(arc
							(start -0.4318 0.3302)
							(mid -0.402042 0.402042)
							(end -0.3302 0.4318)
						)
						(arc
							(start 0.3302 0.4318)
							(mid 0.402042 0.402042)
							(end 0.4318 0.3302)
						)
						(arc
							(start 0.4318 -0.3302)
							(mid 0.402042 -0.402042)
							(end 0.3302 -0.4318)
						)
					)
					(width 0)
					(fill yes)
				)
			)
		)
		(pad "2" smd custom
			(at 0 0.762 270)
			(size 0.2159 0.2159)
			(layers "F.Cu" "F.Mask" "F.Paste")
			(net "GB_VDDA")
			(options
				(clearance outline)
				(anchor circle)
			)
			(primitives
				(gr_poly
					(pts
						(arc
							(start -0.3302 -0.4318)
							(mid -0.402042 -0.402042)
							(end -0.4318 -0.3302)
						)
						(arc
							(start -0.4318 0.3302)
							(mid -0.402042 0.402042)
							(end -0.3302 0.4318)
						)
						(arc
							(start 0.3302 0.4318)
							(mid 0.402042 0.402042)
							(end 0.4318 0.3302)
						)
						(arc
							(start 0.4318 -0.3302)
							(mid 0.402042 -0.402042)
							(end 0.3302 -0.4318)
						)
					)
					(width 0)
					(fill yes)
				)
			)
		)
	)
	(footprint ""
		(layer "F.Cu")
		(at 118.364 -33.02)
		(property "Reference" "STP45"
			(at 0 0 0)
			(layer "F.SilkS")
			(hide yes)
			(effects
				(font
					(size 1.27 1.27)
				)
			)
		)
		(property "Value" "TPAD28"
			(at 0.0127 -1.8034 0)
			(unlocked yes)
			(layer "F.Fab")
			(hide yes)
			(effects
				(font
					(size 1.016 1.016)
					(thickness 0.1524)
				)
			)
		)
		(property "Device Type" "TPAD28"
			(at 0.0127 -3.3274 0)
			(unlocked yes)
			(layer "F.Fab")
			(hide yes)
			(effects
				(font
					(size 1.016 1.016)
					(thickness 0.1524)
				)
			)
		)
		(duplicate_pad_numbers_are_jumpers no)
		(fp_poly
			(pts
				(arc
					(start 0.3556 0)
					(mid -0.3556 0)
					(end 0.3556 0)
				)
			)
			(stroke
				(width 0)
				(type default)
			)
			(fill no)
			(layer "F.CrtYd")
		)
		(fp_poly
			(pts
				(arc
					(start 0.6096 0)
					(mid -0.6096 0)
					(end 0.6096 0)
				)
			)
			(stroke
				(width 0)
				(type default)
			)
			(fill no)
			(layer "F.Fab")
		)
		(pad "1" smd circle
			(at 0 0)
			(size 0.7112 0.7112)
			(layers "F.Cu" "F.Mask" "F.Paste")
			(net "IOC_GPIO_11")
		)
	)
	(footprint ""
		(layer "F.Cu")
		(at 278.765 -200.914)
		(property "Reference" "C187"
			(at 0 0 0)
			(layer "F.SilkS")
			(hide yes)
			(effects
				(font
					(size 1.27 1.27)
				)
			)
		)
		(property "Value" "SCD1U16V2KX-3GP"
			(at 1.1811 -2.7051 0)
			(unlocked yes)
			(layer "F.Fab")
			(hide yes)
			(effects
				(font
					(size 1.016 1.016)
					(thickness 0.1524)
				)
			)
		)
		(property "Device Type" "C402H22"
			(at 1.1811 -4.2291 0)
			(unlocked yes)
			(layer "F.Fab")
			(hide yes)
			(effects
				(font
					(size 1.016 1.016)
					(thickness 0.1524)
				)
			)
		)
		(duplicate_pad_numbers_are_jumpers no)
		(fp_rect
			(start -0.4318 0.9525)
			(end 0.4318 -0.9525)
			(stroke
				(width 0)
				(type default)
			)
			(fill no)
			(layer "F.CrtYd")
		)
		(fp_rect
			(start -0.4318 0.9525)
			(end 0.4318 -0.9525)
			(stroke
				(width 0)
				(type default)
			)
			(fill no)
			(layer "F.Fab")
		)
		(pad "1" smd custom
			(at 0 -0.4445)
			(size 0.1524 0.1524)
			(layers "F.Cu" "F.Mask" "F.Paste")
			(net "P3V3_STBY")
			(options
				(clearance outline)
				(anchor circle)
			)
			(primitives
				(gr_poly
					(pts
						(arc
							(start 0.3048 -0.2032)
							(mid 0.275042 -0.275042)
							(end 0.2032 -0.3048)
						)
						(arc
							(start -0.2032 -0.3048)
							(mid -0.275042 -0.275042)
							(end -0.3048 -0.2032)
						)
						(arc
							(start -0.3048 0.2032)
							(mid -0.275042 0.275042)
							(end -0.2032 0.3048)
						)
						(arc
							(start 0.2032 0.3048)
							(mid 0.275042 0.275042)
							(end 0.3048 0.2032)
						)
					)
					(width 0)
					(fill yes)
				)
			)
		)
		(pad "2" smd custom
			(at 0 0.4445)
			(size 0.1524 0.1524)
			(layers "F.Cu" "F.Mask" "F.Paste")
			(net "GND")
			(options
				(clearance outline)
				(anchor circle)
			)
			(primitives
				(gr_poly
					(pts
						(arc
							(start 0.3048 -0.2032)
							(mid 0.275042 -0.275042)
							(end 0.2032 -0.3048)
						)
						(arc
							(start -0.2032 -0.3048)
							(mid -0.275042 -0.275042)
							(end -0.3048 -0.2032)
						)
						(arc
							(start -0.3048 0.2032)
							(mid -0.275042 0.275042)
							(end -0.2032 0.3048)
						)
						(arc
							(start 0.2032 0.3048)
							(mid 0.275042 0.275042)
							(end 0.3048 0.2032)
						)
					)
					(width 0)
					(fill yes)
				)
			)
		)
	)
	(footprint ""
		(layer "F.Cu")
		(at 310.515 -110.236 180)
		(property "Reference" "PR36"
			(at 0 0 180)
			(layer "F.SilkS")
			(hide yes)
			(effects
				(font
					(size 1.27 1.27)
				)
			)
		)
		(property "Value" "0R2J-2-GP"
			(at 0.064008 -3.993896 180)
			(unlocked yes)
			(layer "F.Fab")
			(hide yes)
			(effects
				(font
					(size 1.016 1.016)
					(thickness 0.1524)
				)
			)
		)
		(property "Device Type" "R402H16"
			(at 0.064008 -5.517896 180)
			(unlocked yes)
			(layer "F.Fab")
			(hide yes)
			(effects
				(font
					(size 1.016 1.016)
					(thickness 0.1524)
				)
			)
		)
		(duplicate_pad_numbers_are_jumpers no)
		(fp_line
			(start 0.508 -0.9398)
			(end -0.508 -0.9398)
			(stroke
				(width 0.1524)
				(type default)
			)
			(layer "F.SilkS")
		)
		(fp_line
			(start -0.508 -0.9398)
			(end -0.508 0.9398)
			(stroke
				(width 0.1524)
				(type default)
			)
			(layer "F.SilkS")
		)
		(fp_rect
			(start -0.508 0.9398)
			(end 0.508 -0.9398)
			(stroke
				(width 0)
				(type default)
			)
			(fill no)
			(layer "F.CrtYd")
		)
		(fp_rect
			(start -0.508 0.9398)
			(end 0.508 -0.9398)
			(stroke
				(width 0)
				(type default)
			)
			(fill no)
			(layer "F.Fab")
		)
		(pad "1" smd custom
			(at 0 -0.4445 180)
			(size 0.1397 0.1397)
			(layers "F.Cu" "F.Mask" "F.Paste")
			(net "P3V3_STBY_ROVP")
			(options
				(clearance outline)
				(anchor circle)
			)
			(primitives
				(gr_poly
					(pts
						(arc
							(start -0.1778 -0.2794)
							(mid -0.249642 -0.249642)
							(end -0.2794 -0.1778)
						)
						(arc
							(start -0.2794 0.1778)
							(mid -0.249642 0.249642)
							(end -0.1778 0.2794)
						)
						(arc
							(start 0.1778 0.2794)
							(mid 0.249642 0.249642)
							(end 0.2794 0.1778)
						)
						(arc
							(start 0.2794 -0.1778)
							(mid 0.249642 -0.249642)
							(end 0.1778 -0.2794)
						)
					)
					(width 0)
					(fill yes)
				)
			)
		)
		(pad "2" smd custom
			(at 0 0.4445 180)
			(size 0.1397 0.1397)
			(layers "F.Cu" "F.Mask" "F.Paste")
			(net "AGND_P3V3_STBY")
			(options
				(clearance outline)
				(anchor circle)
			)
			(primitives
				(gr_poly
					(pts
						(arc
							(start -0.1778 -0.2794)
							(mid -0.249642 -0.249642)
							(end -0.2794 -0.1778)
						)
						(arc
							(start -0.2794 0.1778)
							(mid -0.249642 0.249642)
							(end -0.1778 0.2794)
						)
						(arc
							(start 0.1778 0.2794)
							(mid 0.249642 0.249642)
							(end 0.2794 0.1778)
						)
						(arc
							(start 0.2794 -0.1778)
							(mid 0.249642 -0.249642)
							(end 0.1778 -0.2794)
						)
					)
					(width 0)
					(fill yes)
				)
			)
		)
	)
	(footprint ""
		(layer "F.Cu")
		(at 86.49716 -34.671 -90)
		(property "Reference" "SC880"
			(at 0 0 270)
			(layer "F.SilkS")
			(hide yes)
			(effects
				(font
					(size 1.27 1.27)
				)
			)
		)
		(property "Value" "SCD01U10V1KX-GP"
			(at -2.8321 -1.7399 270)
			(unlocked yes)
			(layer "F.Fab")
			(hide yes)
			(effects
				(font
					(size 1.016 1.016)
					(thickness 0.1524)
				)
			)
		)
		(property "Device Type" "C0201H13"
			(at -2.8321 -3.2639 270)
			(unlocked yes)
			(layer "F.Fab")
			(hide yes)
			(effects
				(font
					(size 1.016 1.016)
					(thickness 0.1524)
				)
			)
		)
		(duplicate_pad_numbers_are_jumpers no)
		(fp_rect
			(start -0.2794 0.6477)
			(end 0.2794 -0.6477)
			(stroke
				(width 0)
				(type default)
			)
			(fill no)
			(layer "F.CrtYd")
		)
		(fp_rect
			(start -0.2794 0.6477)
			(end 0.2794 -0.6477)
			(stroke
				(width 0)
				(type default)
			)
			(fill no)
			(layer "F.Fab")
		)
		(pad "1" smd custom
			(at 0 -0.2794 270)
			(size 0.0762 0.0762)
			(layers "F.Cu" "F.Mask" "F.Paste")
			(net "SAS3008_RAID_TX_C_N1")
			(options
				(clearance outline)
				(anchor circle)
			)
			(primitives
				(gr_poly
					(pts
						(arc
							(start 0.1524 -0.127)
							(mid 0.137521 -0.162921)
							(end 0.1016 -0.1778)
						)
						(arc
							(start -0.1016 -0.1778)
							(mid -0.137521 -0.162921)
							(end -0.1524 -0.127)
						)
						(arc
							(start -0.1524 0.127)
							(mid -0.137521 0.162921)
							(end -0.1016 0.1778)
						)
						(arc
							(start 0.1016 0.1778)
							(mid 0.137521 0.162921)
							(end 0.1524 0.127)
						)
					)
					(width 0)
					(fill yes)
				)
			)
		)
		(pad "2" smd custom
			(at 0 0.2794 270)
			(size 0.0762 0.0762)
			(layers "F.Cu" "F.Mask" "F.Paste")
			(net "SAS3008_RAID_TX_N1")
			(options
				(clearance outline)
				(anchor circle)
			)
			(primitives
				(gr_poly
					(pts
						(arc
							(start 0.1524 -0.127)
							(mid 0.137521 -0.162921)
							(end 0.1016 -0.1778)
						)
						(arc
							(start -0.1016 -0.1778)
							(mid -0.137521 -0.162921)
							(end -0.1524 -0.127)
						)
						(arc
							(start -0.1524 0.127)
							(mid -0.137521 0.162921)
							(end -0.1016 0.1778)
						)
						(arc
							(start 0.1016 0.1778)
							(mid 0.137521 0.162921)
							(end 0.1524 0.127)
						)
					)
					(width 0)
					(fill yes)
				)
			)
		)
	)
)
